FILE_TYPE = CONNECTIVITY;
{Allegro Design Entry HDL 17.4-2019 S026 (4007227) 1/17/2022}
"PAGE_NUMBER" = 388;
0"NC";
1"P0V9_CPU0_RT_2D\g";
2"GND\g";
3"P0V9_CPU0_RT0_2A\g";
4"GND\g";
5"P1V8_CPU0_RT_1D\g";
6"GND\g";
7"P1V8_CPU0_RT0_1A\g";
8"GND\g";
9"GND\g";
10"GND\g";
11"P1V8_CPU0_RT0_1A_1D\g";
12"GND\g";
13"P0V9_CPU0_RT0_2A_2D\g";
%"Q_RES"
"2","(-4300,2775)","2","pure_quanta","I10";
;
LOCATION"R961"
$SEC"1"
CDS_SEC"1"
MATERIAL"EMPTY"
PACK_TYPE"0603LF"
WATTAGE"1/4W"
VALUE"0"
TOLERANCE"5%"
CDS_LIB"pure_quanta"
PART_NUMBER"CS00006J900";
"A"
$PN"1"1;
"B"
$PN"2"13;
%"Q_CAPP"
"1","(-750,2250)","0","pure_quanta","I100";
;
LOCATION"C7009"
$SEC"1"
CDS_SEC"1"
VALUE"470UF"
TOLERANCE"20%"
MATERIAL"SPCAP"
PACK_TYPE"SMLF"
VOLTAGE"2.5V"
CDS_LIB"pure_quanta"
PART_NUMBER"CH747LM8818";
"A"
$PN"1"3;
"B"
$PN"2"10;
%"Q_CAP"
"1","(-475,2250)","0","pure_quanta","I101";
;
LOCATION"C7010"
$SEC"1"
CDS_SEC"1"
TOLERANCE"20%"
MATERIAL"X6S"
PACK_TYPE"C0805"
VALUE"100UF"
VOLTAGE"4V"
CDS_LIB"pure_quanta"
PART_NUMBER"CH710KMEA01";
"B"
$PN"2"10;
"A"
$PN"1"3;
%"Q_CAPP"
"1","(-2000,4875)","0","pure_quanta","I102";
;
LOCATION"C7032"
$SEC"1"
CDS_SEC"1"
PACK_TYPE"SMLF"
MATERIAL"SPCAP"
VOLTAGE"2.5V"
TOLERANCE"20%"
VALUE"470UF"
CDS_LIB"pure_quanta"
PART_NUMBER"CH747LM8818";
"A"
$PN"1"1;
"B"
$PN"2"2;
%"Q_CAP"
"1","(-1650,4875)","0","pure_quanta","I103";
;
LOCATION"C7033"
$SEC"1"
CDS_SEC"1"
MATERIAL"X6S"
VALUE"47UF"
PACK_TYPE"C0805"
VOLTAGE"4V"
TOLERANCE"20%"
CDS_LIB"pure_quanta"
PART_NUMBER"CH647KMEA04";
"B"
$PN"2"2;
"A"
$PN"1"1;
%"Q_CAP"
"1","(-1375,4875)","0","pure_quanta","I104";
;
LOCATION"C7034"
$SEC"1"
CDS_SEC"1"
VALUE"47UF"
MATERIAL"X6S"
PACK_TYPE"C0805"
TOLERANCE"20%"
VOLTAGE"4V"
CDS_LIB"pure_quanta"
PART_NUMBER"CH647KMEA04";
"B"
$PN"2"2;
"A"
$PN"1"1;
%"Q_CAP"
"1","(-1125,4875)","0","pure_quanta","I105";
;
LOCATION"C7035"
$SEC"1"
CDS_SEC"1"
VALUE"47UF"
VOLTAGE"4V"
PACK_TYPE"C0805"
MATERIAL"X6S"
TOLERANCE"20%"
CDS_LIB"pure_quanta"
PART_NUMBER"CH647KMEA04";
"B"
$PN"2"2;
"A"
$PN"1"1;
%"Q_CAP"
"1","(-850,4875)","0","pure_quanta","I106";
;
LOCATION"C7036"
$SEC"1"
CDS_SEC"1"
VOLTAGE"4V"
MATERIAL"X6S"
VALUE"47UF"
TOLERANCE"20%"
PACK_TYPE"C0805"
CDS_LIB"pure_quanta"
PART_NUMBER"CH647KMEA04";
"B"
$PN"2"2;
"A"
$PN"1"1;
%"Q_RES"
"1","(-3925,2500)","0","pure_quanta","I11";
;
LOCATION"R962"
$SEC"1"
CDS_SEC"1"
TOLERANCE"5%"
MATERIAL"CHIP"
VALUE"0"
WATTAGE"1/4W"
PACK_TYPE"0603LF"
CDS_LIB"pure_quanta"
PART_NUMBER"CS00006J900";
"B"
$PN"2"3;
"A"
$PN"1"13;
%"Q_INDUCTOR"
"1","(-7775,4475)","0","pure_quanta","I12";
;
LOCATION"L11"
$SEC"1"
CDS_SEC"1"
PACK_TYPE"SMLF"
MATERIAL"IND"
VALUE"BLM21SN300SN1D/5A"
CDS_LIB"pure_quanta"
NEEDS_NO_SIZE"TRUE"
PART_NUMBER"CX300SN1000";
"1"
$PN"1"5;
"2"
$PN"2"7;
%"Q_CAP"
"1","(-7200,4200)","0","pure_quanta","I13";
;
LOCATION"C503"
$SEC"1"
CDS_SEC"1"
VALUE"100UF"
PACK_TYPE"C0805"
VOLTAGE"4V"
MATERIAL"X6S"
TOLERANCE"20%"
CDS_LIB"pure_quanta"
PART_NUMBER"CH710KMEA01";
"B"
$PN"2"8;
"A"
$PN"1"7;
%"Q_CAP"
"1","(-6975,4200)","0","pure_quanta","I14";
;
LOCATION"C505"
$SEC"1"
CDS_SEC"1"
TOLERANCE"20%"
PACK_TYPE"C0402"
VALUE"22UF"
MATERIAL"X6S"
VOLTAGE"4V"
CDS_LIB"pure_quanta"
PART_NUMBER"CH622KMEB02";
"B"
$PN"2"8;
"A"
$PN"1"7;
%"P1V0"
"1","(-7300,4675)","0","pure_quanta_power","I15";
;
HDL_POWER"P1V8_CPU0_RT0_1A"
CDS_LIB"pure_quanta_power";
"A"7;
%"Q_CAP"
"1","(-7050,5025)","0","pure_quanta","I16";
;
LOCATION"C502"
$SEC"1"
CDS_SEC"1"
VOLTAGE"4V"
PACK_TYPE"C0805"
VALUE"100UF"
TOLERANCE"20%"
MATERIAL"X6S"
CDS_LIB"pure_quanta"
PART_NUMBER"CH710KMEA01";
"B"
$PN"2"6;
"A"
$PN"1"5;
%"Q_CAP"
"1","(-6775,4200)","0","pure_quanta","I17";
;
LOCATION"C507"
$SEC"1"
CDS_SEC"1"
VOLTAGE"6.3V"
VALUE"10UF"
MATERIAL"X6S"
PACK_TYPE"C0402"
TOLERANCE"20%"
CDS_LIB"pure_quanta"
PART_NUMBER"CH6101MEB01";
"B"
$PN"2"8;
"A"
$PN"1"7;
%"Q_CAP"
"1","(-6575,4200)","0","pure_quanta","I18";
;
LOCATION"C510"
$SEC"1"
CDS_SEC"1"
PACK_TYPE"0402"
MATERIAL"X6S"
VOLTAGE"6.3V"
VALUE"4.7UF"
TOLERANCE"20%"
CDS_LIB"pure_quanta"
PART_NUMBER"CH5471MEB01";
"B"
$PN"2"8;
"A"
$PN"1"7;
%"Q_CAP"
"1","(-6350,4200)","0","pure_quanta","I19";
;
LOCATION"C512"
$SEC"1"
CDS_SEC"1"
PACK_TYPE"0201"
MATERIAL"X6S"
VOLTAGE"4V"
VALUE"1UF"
TOLERANCE"20%"
CDS_LIB"pure_quanta"
PART_NUMBER"CH-10KMEE00";
"B"
$PN"2"8;
"A"
$PN"1"7;
%"UNIVERSAL_GND"
"1","(-6375,4725)","0","pure_quanta_power","I20";
;
CDS_LIB"pure_quanta_power"
HDL_POWER"GND";
"A"6;
%"UNIVERSAL_GND"
"1","(-6150,3875)","0","pure_quanta_power","I21";
;
CDS_LIB"pure_quanta_power"
HDL_POWER"GND";
"A"8;
%"Q_CAP"
"1","(-6150,4200)","0","pure_quanta","I22";
;
LOCATION"C514"
$SEC"1"
CDS_SEC"1"
MATERIAL"X6S"
VOLTAGE"4V"
VALUE"1UF"
PACK_TYPE"0201"
TOLERANCE"20%"
CDS_LIB"pure_quanta"
PART_NUMBER"CH-10KMEE00";
"B"
$PN"2"8;
"A"
$PN"1"7;
%"Q_CAP"
"1","(-5925,4200)","0","pure_quanta","I23";
;
LOCATION"C515"
$SEC"1"
CDS_SEC"1"
TOLERANCE"10%"
VOLTAGE"10V"
VALUE"0.1UF"
PACK_TYPE"C0201"
MATERIAL"X7S"
CDS_LIB"pure_quanta"
PART_NUMBER"CH4102K6E00";
"B"
$PN"2"8;
"A"
$PN"1"7;
%"Q_CAP"
"1","(-6800,5025)","0","pure_quanta","I24";
;
LOCATION"C504"
$SEC"1"
CDS_SEC"1"
TOLERANCE"20%"
MATERIAL"X6S"
VOLTAGE"4V"
VALUE"22UF"
PACK_TYPE"C0402"
CDS_LIB"pure_quanta"
PART_NUMBER"CH622KMEB02";
"B"
$PN"2"6;
"A"
$PN"1"5;
%"Q_CAP"
"1","(-6550,5000)","0","pure_quanta","I25";
;
LOCATION"C506"
$SEC"1"
CDS_SEC"1"
PACK_TYPE"C0402"
TOLERANCE"20%"
VOLTAGE"6.3V"
VALUE"10UF"
MATERIAL"X6S"
CDS_LIB"pure_quanta"
PART_NUMBER"CH6101MEB01";
"B"
$PN"2"6;
"A"
$PN"1"5;
%"Q_CAP"
"1","(-6300,5000)","0","pure_quanta","I26";
;
LOCATION"C511"
$SEC"1"
CDS_SEC"1"
PACK_TYPE"0402"
VALUE"4.7UF"
MATERIAL"X6S"
VOLTAGE"6.3V"
TOLERANCE"20%"
CDS_LIB"pure_quanta"
PART_NUMBER"CH5471MEB01";
"B"
$PN"2"6;
"A"
$PN"1"5;
%"Q_CAP"
"1","(-5675,4200)","0","pure_quanta","I27";
;
LOCATION"C517"
$SEC"1"
CDS_SEC"1"
VALUE"0.1UF"
VOLTAGE"10V"
MATERIAL"X7S"
PACK_TYPE"C0201"
TOLERANCE"10%"
CDS_LIB"pure_quanta"
PART_NUMBER"CH4102K6E00";
"B"
$PN"2"8;
"A"
$PN"1"7;
%"Q_CAP"
"1","(-5425,4200)","0","pure_quanta","I28";
;
LOCATION"C519"
$SEC"1"
CDS_SEC"1"
VALUE"0.1UF"
VOLTAGE"10V"
TOLERANCE"10%"
PACK_TYPE"C0201"
MATERIAL"X7S"
CDS_LIB"pure_quanta"
PART_NUMBER"CH4102K6E00";
"B"
$PN"2"8;
"A"
$PN"1"7;
%"Q_CAP"
"1","(-5150,4200)","0","pure_quanta","I29";
;
LOCATION"C520"
$SEC"1"
CDS_SEC"1"
VALUE"0.1UF"
MATERIAL"X7S"
TOLERANCE"10%"
PACK_TYPE"C0201"
VOLTAGE"10V"
CDS_LIB"pure_quanta"
PART_NUMBER"CH4102K6E00";
"B"
$PN"2"8;
"A"
$PN"1"7;
%"P1V0"
"1","(-8150,5300)","0","pure_quanta_power","I3";
;
HDL_POWER"P1V8_CPU0_RT_1D"
CDS_LIB"pure_quanta_power";
"A"5;
%"Q_INDUCTOR"
"1","(-3825,4475)","0","pure_quanta","I30";
;
LOCATION"L12"
$SEC"1"
CDS_SEC"1"
PACK_TYPE"SMLF"
VALUE"100NH/16A"
MATERIAL"IND"
NEEDS_NO_SIZE"TRUE"
CDS_LIB"pure_quanta"
PART_NUMBER"CV+10G0MZ04";
"1"
$PN"1"1;
"2"
$PN"2"3;
%"VCC_CORE"
"1","(-4300,5975)","0","pure_quanta_power","I31";
;
HDL_POWER"P0V9_CPU0_RT_2D"
CDS_LIB"pure_quanta_power";
"A"1;
%"Q_CAP"
"1","(-3025,1150)","0","pure_quanta","I32";
;
LOCATION"C538"
$SEC"1"
CDS_SEC"1"
MATERIAL"X7S"
PACK_TYPE"C0201"
TOLERANCE"10%"
VOLTAGE"10V"
VALUE"0.1UF"
CDS_LIB"pure_quanta"
PART_NUMBER"CH4102K6E00";
"B"
$PN"2"12;
"A"
$PN"1"13;
%"VCC_CORE"
"1","(-3150,1675)","0","pure_quanta_power","I33";
;
HDL_POWER"P0V9_CPU0_RT0_2A_2D"
CDS_LIB"pure_quanta_power";
"A"13;
%"UNIVERSAL_GND"
"1","(-2325,825)","0","pure_quanta_power","I35";
;
CDS_LIB"pure_quanta_power"
HDL_POWER"GND";
"A"12;
%"Q_CAP"
"1","(-2475,1150)","0","pure_quanta","I36";
;
LOCATION"C544"
$SEC"1"
CDS_SEC"1"
TOLERANCE"10%"
PACK_TYPE"C0201"
MATERIAL"X7S"
VOLTAGE"10V"
VALUE"0.1UF"
CDS_LIB"pure_quanta"
PART_NUMBER"CH4102K6E00";
"B"
$PN"2"12;
"A"
$PN"1"13;
%"Q_CAP"
"1","(-3200,2250)","0","pure_quanta","I38";
;
LOCATION"C576"
$SEC"1"
CDS_SEC"1"
VOLTAGE"10V"
PACK_TYPE"C0201"
MATERIAL"X7S"
TOLERANCE"10%"
VALUE"0.1UF"
CDS_LIB"pure_quanta"
PART_NUMBER"CH4102K6E00";
"B"
$PN"2"10;
"A"
$PN"1"3;
%"Q_CAP"
"1","(-2900,2250)","0","pure_quanta","I39";
;
LOCATION"C580"
$SEC"1"
CDS_SEC"1"
VALUE"0.1UF"
VOLTAGE"10V"
TOLERANCE"10%"
MATERIAL"X7S"
PACK_TYPE"C0201"
CDS_LIB"pure_quanta"
PART_NUMBER"CH4102K6E00";
"B"
$PN"2"10;
"A"
$PN"1"3;
%"Q_RES"
"1","(-7700,3575)","0","pure_quanta","I4";
;
LOCATION"R952"
SEC"1"
VALUE"0"
MATERIAL"EMPTY"
PACK_TYPE"0402LF"
TOLERANCE"5%"
WATTAGE"1/16W"
CDS_LIB"pure_quanta"
SEC_TYPE"0402LF"
PART_NUMBER"CS00002JB13";
"B"
$PN"2"7;
"A"
$PN"1"11;
%"Q_CAP"
"1","(-3475,2950)","0","pure_quanta","I40";
;
LOCATION"C555"
$SEC"1"
CDS_SEC"1"
MATERIAL"X6S"
VALUE"1UF"
PACK_TYPE"0201"
VOLTAGE"4V"
TOLERANCE"20%"
CDS_LIB"pure_quanta"
PART_NUMBER"CH-10KMEE00";
"B"
$PN"2"4;
"A"
$PN"1"3;
%"Q_CAP"
"1","(-3475,3575)","0","pure_quanta","I41";
;
LOCATION"C561"
$SEC"1"
CDS_SEC"1"
PACK_TYPE"C0402"
MATERIAL"X6S"
TOLERANCE"20%"
VOLTAGE"6.3V"
VALUE"10UF"
CDS_LIB"pure_quanta"
PART_NUMBER"CH6101MEB01";
"B"
$PN"2"4;
"A"
$PN"1"3;
%"Q_CAP"
"1","(-3250,2950)","0","pure_quanta","I42";
;
LOCATION"C539"
$SEC"1"
CDS_SEC"1"
MATERIAL"X6S"
VALUE"1UF"
VOLTAGE"4V"
TOLERANCE"20%"
PACK_TYPE"0201"
CDS_LIB"pure_quanta"
PART_NUMBER"CH-10KMEE00";
"B"
$PN"2"4;
"A"
$PN"1"3;
%"Q_CAP"
"1","(-3000,2950)","0","pure_quanta","I43";
;
LOCATION"C562"
$SEC"1"
CDS_SEC"1"
MATERIAL"X6S"
VOLTAGE"4V"
VALUE"1UF"
TOLERANCE"20%"
PACK_TYPE"0201"
CDS_LIB"pure_quanta"
PART_NUMBER"CH-10KMEE00";
"B"
$PN"2"4;
"A"
$PN"1"3;
%"Q_CAP"
"1","(-3250,3575)","0","pure_quanta","I44";
;
LOCATION"C579"
$SEC"1"
CDS_SEC"1"
TOLERANCE"20%"
VALUE"10UF"
PACK_TYPE"C0402"
VOLTAGE"6.3V"
MATERIAL"X6S"
CDS_LIB"pure_quanta"
PART_NUMBER"CH6101MEB01";
"B"
$PN"2"4;
"A"
$PN"1"3;
%"Q_CAP"
"1","(-3025,3575)","0","pure_quanta","I45";
;
LOCATION"C554"
$SEC"1"
CDS_SEC"1"
PACK_TYPE"0402"
MATERIAL"X6S"
VALUE"4.7UF"
TOLERANCE"20%"
VOLTAGE"6.3V"
CDS_LIB"pure_quanta"
PART_NUMBER"CH5471MEB01";
"B"
$PN"2"4;
"A"
$PN"1"3;
%"Q_CAP"
"1","(-2800,3575)","0","pure_quanta","I46";
;
LOCATION"C571"
$SEC"1"
CDS_SEC"1"
VOLTAGE"6.3V"
VALUE"4.7UF"
MATERIAL"X6S"
PACK_TYPE"0402"
TOLERANCE"20%"
CDS_LIB"pure_quanta"
PART_NUMBER"CH5471MEB01";
"B"
$PN"2"4;
"A"
$PN"1"3;
%"Q_CAP"
"1","(-2675,2250)","0","pure_quanta","I48";
;
LOCATION"C541"
$SEC"1"
CDS_SEC"1"
VOLTAGE"10V"
PACK_TYPE"C0201"
MATERIAL"X7S"
TOLERANCE"10%"
VALUE"0.1UF"
CDS_LIB"pure_quanta"
PART_NUMBER"CH4102K6E00";
"B"
$PN"2"10;
"A"
$PN"1"3;
%"Q_CAP"
"1","(-2425,2250)","0","pure_quanta","I49";
;
LOCATION"C582"
$SEC"1"
CDS_SEC"1"
TOLERANCE"10%"
MATERIAL"X7S"
PACK_TYPE"C0201"
VOLTAGE"10V"
VALUE"0.1UF"
CDS_LIB"pure_quanta"
PART_NUMBER"CH4102K6E00";
"B"
$PN"2"10;
"A"
$PN"1"3;
%"Q_RES"
"1","(-7700,3775)","0","pure_quanta","I5";
;
LOCATION"R951"
SEC"1"
MATERIAL"EMPTY"
WATTAGE"1/16W"
PACK_TYPE"0402LF"
TOLERANCE"5%"
VALUE"0"
SEC_TYPE"0402LF"
CDS_LIB"pure_quanta"
PART_NUMBER"CS00002JB13";
"B"
$PN"2"7;
"A"
$PN"1"11;
%"Q_CAP"
"1","(-2175,2250)","0","pure_quanta","I50";
;
LOCATION"C523"
$SEC"1"
CDS_SEC"1"
VALUE"0.1UF"
MATERIAL"X7S"
PACK_TYPE"C0201"
TOLERANCE"10%"
VOLTAGE"10V"
CDS_LIB"pure_quanta"
PART_NUMBER"CH4102K6E00";
"B"
$PN"2"10;
"A"
$PN"1"3;
%"Q_CAP"
"1","(-1900,2250)","0","pure_quanta","I51";
;
LOCATION"C585"
$SEC"1"
CDS_SEC"1"
TOLERANCE"10%"
VOLTAGE"10V"
PACK_TYPE"C0201"
MATERIAL"X7S"
VALUE"0.1UF"
CDS_LIB"pure_quanta"
PART_NUMBER"CH4102K6E00";
"B"
$PN"2"10;
"A"
$PN"1"3;
%"Q_CAP"
"1","(-2725,2950)","0","pure_quanta","I52";
;
LOCATION"C570"
$SEC"1"
CDS_SEC"1"
VALUE"1UF"
MATERIAL"X6S"
VOLTAGE"4V"
TOLERANCE"20%"
PACK_TYPE"0201"
CDS_LIB"pure_quanta"
PART_NUMBER"CH-10KMEE00";
"B"
$PN"2"4;
"A"
$PN"1"3;
%"Q_CAP"
"1","(-2450,2950)","0","pure_quanta","I53";
;
LOCATION"C573"
$SEC"1"
CDS_SEC"1"
PACK_TYPE"0201"
TOLERANCE"20%"
VALUE"1UF"
VOLTAGE"4V"
MATERIAL"X6S"
CDS_LIB"pure_quanta"
PART_NUMBER"CH-10KMEE00";
"B"
$PN"2"4;
"A"
$PN"1"3;
%"Q_CAP"
"1","(-2550,3575)","0","pure_quanta","I54";
;
LOCATION"C557"
$SEC"1"
CDS_SEC"1"
PACK_TYPE"0402"
MATERIAL"X6S"
TOLERANCE"20%"
VALUE"4.7UF"
VOLTAGE"6.3V"
CDS_LIB"pure_quanta"
PART_NUMBER"CH5471MEB01";
"B"
$PN"2"4;
"A"
$PN"1"3;
%"Q_CAP"
"1","(-2325,3575)","0","pure_quanta","I55";
;
LOCATION"C572"
$SEC"1"
CDS_SEC"1"
PACK_TYPE"0402"
VOLTAGE"6.3V"
VALUE"4.7UF"
TOLERANCE"20%"
MATERIAL"X6S"
CDS_LIB"pure_quanta"
PART_NUMBER"CH5471MEB01";
"B"
$PN"2"4;
"A"
$PN"1"3;
%"Q_CAP"
"1","(-2200,2925)","0","pure_quanta","I56";
;
LOCATION"C577"
$SEC"1"
CDS_SEC"1"
MATERIAL"X6S"
VALUE"1UF"
VOLTAGE"4V"
TOLERANCE"20%"
PACK_TYPE"0201"
CDS_LIB"pure_quanta"
PART_NUMBER"CH-10KMEE00";
"B"
$PN"2"4;
"A"
$PN"1"3;
%"Q_CAP"
"1","(-1925,2925)","0","pure_quanta","I57";
;
LOCATION"C581"
$SEC"1"
CDS_SEC"1"
TOLERANCE"20%"
MATERIAL"X6S"
VALUE"1UF"
VOLTAGE"4V"
PACK_TYPE"0201"
CDS_LIB"pure_quanta"
PART_NUMBER"CH-10KMEE00";
"B"
$PN"2"4;
"A"
$PN"1"3;
%"Q_CAP"
"1","(-2100,3575)","0","pure_quanta","I58";
;
LOCATION"C525"
$SEC"1"
CDS_SEC"1"
PACK_TYPE"0201"
VOLTAGE"4V"
VALUE"1UF"
TOLERANCE"20%"
MATERIAL"X6S"
CDS_LIB"pure_quanta"
PART_NUMBER"CH-10KMEE00";
"B"
$PN"2"4;
"A"
$PN"1"3;
%"Q_CAP"
"1","(-1875,3575)","0","pure_quanta","I59";
;
LOCATION"C529"
$SEC"1"
CDS_SEC"1"
VOLTAGE"4V"
PACK_TYPE"0201"
VALUE"1UF"
MATERIAL"X6S"
TOLERANCE"20%"
CDS_LIB"pure_quanta"
PART_NUMBER"CH-10KMEE00";
"B"
$PN"2"4;
"A"
$PN"1"3;
%"P1V0"
"1","(-6900,3500)","0","pure_quanta_power","I6";
;
HDL_POWER"P1V8_CPU0_RT0_1A_1D"
CDS_LIB"pure_quanta_power";
"A"11;
%"Q_CAP"
"1","(-1625,2250)","0","pure_quanta","I60";
;
LOCATION"C558"
$SEC"1"
CDS_SEC"1"
TOLERANCE"10%"
VOLTAGE"10V"
VALUE"0.1UF"
PACK_TYPE"C0201"
MATERIAL"X7S"
CDS_LIB"pure_quanta"
PART_NUMBER"CH4102K6E00";
"B"
$PN"2"10;
"A"
$PN"1"3;
%"UNIVERSAL_GND"
"1","(-1375,1825)","0","pure_quanta_power","I61";
;
CDS_LIB"pure_quanta_power"
HDL_POWER"GND";
"A"10;
%"Q_CAP"
"1","(-1375,2250)","0","pure_quanta","I62";
;
LOCATION"C543"
$SEC"1"
CDS_SEC"1"
MATERIAL"X7S"
VALUE"0.1UF"
VOLTAGE"10V"
TOLERANCE"10%"
PACK_TYPE"C0201"
CDS_LIB"pure_quanta"
PART_NUMBER"CH4102K6E00";
"B"
$PN"2"10;
"A"
$PN"1"3;
%"UNIVERSAL_GND"
"1","(-875,2550)","0","pure_quanta_power","I63";
;
CDS_LIB"pure_quanta_power"
HDL_POWER"GND";
"A"4;
%"Q_CAP"
"1","(-1650,3575)","0","pure_quanta","I65";
;
LOCATION"C521"
$SEC"1"
CDS_SEC"1"
MATERIAL"X6S"
VALUE"1UF"
TOLERANCE"20%"
VOLTAGE"4V"
PACK_TYPE"0201"
CDS_LIB"pure_quanta"
PART_NUMBER"CH-10KMEE00";
"B"
$PN"2"4;
"A"
$PN"1"3;
%"Q_CAP"
"1","(-1400,3575)","0","pure_quanta","I66";
;
LOCATION"C526"
$SEC"1"
CDS_SEC"1"
TOLERANCE"20%"
MATERIAL"X6S"
PACK_TYPE"0201"
VOLTAGE"4V"
VALUE"1UF"
CDS_LIB"pure_quanta"
PART_NUMBER"CH-10KMEE00";
"B"
$PN"2"4;
"A"
$PN"1"3;
%"Q_CAP"
"1","(-3475,4200)","0","pure_quanta","I67";
;
LOCATION"C550"
$SEC"1"
CDS_SEC"1"
TOLERANCE"20%"
VOLTAGE"4V"
MATERIAL"X6S"
PACK_TYPE"C0805"
VALUE"100UF"
CDS_LIB"pure_quanta"
PART_NUMBER"CH710KMEA01";
"B"
$PN"2"4;
"A"
$PN"1"3;
%"VCC_CORE"
"1","(-3350,4725)","0","pure_quanta_power","I68";
;
HDL_POWER"P0V9_CPU0_RT0_2A"
CDS_LIB"pure_quanta_power";
"A"3;
%"Q_CAP"
"1","(-3250,4200)","0","pure_quanta","I69";
;
LOCATION"C556"
$SEC"1"
CDS_SEC"1"
PACK_TYPE"C0805"
TOLERANCE"20%"
VALUE"100UF"
VOLTAGE"4V"
MATERIAL"X6S"
CDS_LIB"pure_quanta"
PART_NUMBER"CH710KMEA01";
"B"
$PN"2"4;
"A"
$PN"1"3;
%"UNIVERSAL_GND"
"1","(-6500,2700)","0","pure_quanta_power","I7";
;
CDS_LIB"pure_quanta_power"
HDL_POWER"GND";
"A"9;
%"Q_CAP"
"1","(-3025,4200)","0","pure_quanta","I70";
;
LOCATION"C560"
$SEC"1"
CDS_SEC"1"
PACK_TYPE"C0805"
TOLERANCE"20%"
VALUE"100UF"
MATERIAL"X6S"
VOLTAGE"4V"
CDS_LIB"pure_quanta"
PART_NUMBER"CH710KMEA01";
"B"
$PN"2"4;
"A"
$PN"1"3;
%"Q_CAP"
"1","(-2800,4200)","0","pure_quanta","I71";
;
LOCATION"C564"
$SEC"1"
CDS_SEC"1"
VALUE"100UF"
VOLTAGE"4V"
TOLERANCE"20%"
MATERIAL"X6S"
PACK_TYPE"C0805"
CDS_LIB"pure_quanta"
PART_NUMBER"CH710KMEA01";
"B"
$PN"2"4;
"A"
$PN"1"3;
%"Q_CAP"
"1","(-4100,5475)","0","pure_quanta","I72";
;
LOCATION"C559"
$SEC"1"
CDS_SEC"1"
VALUE"100UF"
VOLTAGE"4V"
TOLERANCE"20%"
PACK_TYPE"C0805"
MATERIAL"X6S"
CDS_LIB"pure_quanta"
PART_NUMBER"CH710KMEA01";
"B"
$PN"2"2;
"A"
$PN"1"1;
%"Q_CAP"
"1","(-3525,5450)","0","pure_quanta","I73";
;
LOCATION"C574"
$SEC"1"
CDS_SEC"1"
TOLERANCE"20%"
PACK_TYPE"C0402"
MATERIAL"X6S"
VOLTAGE"6.3V"
VALUE"10UF"
CDS_LIB"pure_quanta"
PART_NUMBER"CH6101MEB01";
"B"
$PN"2"2;
"A"
$PN"1"1;
%"Q_CAP"
"1","(-3825,5475)","0","pure_quanta","I74";
;
LOCATION"C563"
$SEC"1"
CDS_SEC"1"
PACK_TYPE"C0402"
MATERIAL"X6S"
TOLERANCE"20%"
VOLTAGE"4V"
VALUE"22UF"
CDS_LIB"pure_quanta"
PART_NUMBER"CH622KMEB02";
"B"
$PN"2"2;
"A"
$PN"1"1;
%"Q_CAP"
"1","(-2550,4200)","0","pure_quanta","I75";
;
LOCATION"C586"
$SEC"1"
CDS_SEC"1"
VALUE"22UF"
TOLERANCE"20%"
PACK_TYPE"C0402"
MATERIAL"X6S"
VOLTAGE"4V"
CDS_LIB"pure_quanta"
PART_NUMBER"CH622KMEB02";
"B"
$PN"2"4;
"A"
$PN"1"3;
%"Q_CAP"
"1","(-2325,4200)","0","pure_quanta","I76";
;
LOCATION"C565"
$SEC"1"
CDS_SEC"1"
PACK_TYPE"C0402"
VALUE"22UF"
VOLTAGE"4V"
MATERIAL"X6S"
TOLERANCE"20%"
CDS_LIB"pure_quanta"
PART_NUMBER"CH622KMEB02";
"B"
$PN"2"4;
"A"
$PN"1"3;
%"Q_CAP"
"1","(-2100,4200)","0","pure_quanta","I77";
;
LOCATION"C575"
$SEC"1"
CDS_SEC"1"
VOLTAGE"4V"
VALUE"22UF"
PACK_TYPE"C0402"
MATERIAL"X6S"
TOLERANCE"20%"
CDS_LIB"pure_quanta"
PART_NUMBER"CH622KMEB02";
"B"
$PN"2"4;
"A"
$PN"1"3;
%"Q_CAP"
"1","(-1875,4200)","0","pure_quanta","I78";
;
LOCATION"C568"
$SEC"1"
CDS_SEC"1"
VALUE"22UF"
PACK_TYPE"C0402"
MATERIAL"X6S"
VOLTAGE"4V"
TOLERANCE"20%"
CDS_LIB"pure_quanta"
PART_NUMBER"CH622KMEB02";
"B"
$PN"2"4;
"A"
$PN"1"3;
%"Q_CAP"
"1","(-3250,5450)","0","pure_quanta","I79";
;
LOCATION"C569"
$SEC"1"
CDS_SEC"1"
MATERIAL"X6S"
PACK_TYPE"0402"
VALUE"4.7UF"
TOLERANCE"20%"
VOLTAGE"6.3V"
CDS_LIB"pure_quanta"
PART_NUMBER"CH5471MEB01";
"B"
$PN"2"2;
"A"
$PN"1"1;
%"Q_CAP"
"1","(-6775,3125)","0","pure_quanta","I8";
;
LOCATION"C513"
$SEC"1"
CDS_SEC"1"
PACK_TYPE"0201"
TOLERANCE"20%"
VOLTAGE"4V"
VALUE"1UF"
MATERIAL"X6S"
CDS_LIB"pure_quanta"
PART_NUMBER"CH-10KMEE00";
"B"
$PN"2"9;
"A"
$PN"1"11;
%"Q_CAP"
"1","(-2950,5450)","0","pure_quanta","I80";
;
LOCATION"C528"
$SEC"1"
CDS_SEC"1"
MATERIAL"X6S"
VOLTAGE"4V"
TOLERANCE"20%"
VALUE"1UF"
PACK_TYPE"0201"
CDS_LIB"pure_quanta"
PART_NUMBER"CH-10KMEE00";
"B"
$PN"2"2;
"A"
$PN"1"1;
%"Q_CAP"
"1","(-2675,5450)","0","pure_quanta","I81";
;
LOCATION"C522"
$SEC"1"
CDS_SEC"1"
VALUE"0.1UF"
MATERIAL"X7S"
VOLTAGE"10V"
TOLERANCE"10%"
PACK_TYPE"C0201"
CDS_LIB"pure_quanta"
PART_NUMBER"CH4102K6E00";
"B"
$PN"2"2;
"A"
$PN"1"1;
%"Q_CAP"
"1","(-1575,4200)","0","pure_quanta","I82";
;
LOCATION"C584"
$SEC"1"
CDS_SEC"1"
PACK_TYPE"C0402"
VALUE"10UF"
VOLTAGE"6.3V"
TOLERANCE"20%"
MATERIAL"X6S"
CDS_LIB"pure_quanta"
PART_NUMBER"CH6101MEB01";
"B"
$PN"2"4;
"A"
$PN"1"3;
%"Q_CAP"
"1","(-1275,4200)","0","pure_quanta","I83";
;
LOCATION"C567"
$SEC"1"
CDS_SEC"1"
PACK_TYPE"C0402"
TOLERANCE"20%"
MATERIAL"X6S"
VOLTAGE"6.3V"
VALUE"10UF"
CDS_LIB"pure_quanta"
PART_NUMBER"CH6101MEB01";
"B"
$PN"2"4;
"A"
$PN"1"3;
%"Q_CAP"
"1","(-2325,5450)","0","pure_quanta","I84";
;
LOCATION"C524"
$SEC"1"
CDS_SEC"1"
TOLERANCE"10%"
MATERIAL"X7S"
VALUE"0.1UF"
VOLTAGE"10V"
PACK_TYPE"C0201"
CDS_LIB"pure_quanta"
PART_NUMBER"CH4102K6E00";
"B"
$PN"2"2;
"A"
$PN"1"1;
%"Q_CAP"
"1","(-2050,5450)","0","pure_quanta","I85";
;
LOCATION"C578"
$SEC"1"
CDS_SEC"1"
TOLERANCE"10%"
PACK_TYPE"C0201"
MATERIAL"X7S"
VALUE"0.1UF"
VOLTAGE"10V"
CDS_LIB"pure_quanta"
PART_NUMBER"CH4102K6E00";
"B"
$PN"2"2;
"A"
$PN"1"1;
%"UNIVERSAL_GND"
"1","(-450,4500)","0","pure_quanta_power","I86";
;
CDS_LIB"pure_quanta_power"
HDL_POWER"GND";
"A"2;
%"Q_CAP"
"1","(-1725,5450)","0","pure_quanta","I87";
;
LOCATION"C540"
$SEC"1"
CDS_SEC"1"
PACK_TYPE"C0201"
MATERIAL"X7S"
TOLERANCE"10%"
VALUE"0.1UF"
VOLTAGE"10V"
CDS_LIB"pure_quanta"
PART_NUMBER"CH4102K6E00";
"B"
$PN"2"2;
"A"
$PN"1"1;
%"Q_INDUCTOR"
"1","(-8225,4125)","3","pure_quanta","I88";
;
LOCATION"L26"
$SEC"1"
CDS_SEC"1"
VALUE"BLM15PD121SN1D/1300MA"
PACK_TYPE"SMLF"
MATERIAL"IND"
NEEDS_NO_SIZE"TRUE"
CDS_LIB"pure_quanta"
PART_NUMBER"CX5PD121000";
"1"
$PN"1"5;
"2"
$PN"2"11;
%"Q_RES"
"2","(-8100,4100)","0","pure_quanta","I89";
;
LOCATION"R960"
$SEC"1"
CDS_SEC"1"
MATERIAL"EMPTY"
WATTAGE"1/16W"
TOLERANCE"5%"
VALUE"0"
PACK_TYPE"0402LF"
CDS_LIB"pure_quanta"
PART_NUMBER"CS00002JB13";
"A"
$PN"1"5;
"B"
$PN"2"11;
%"Q_CAP"
"1","(-6500,3100)","0","pure_quanta","I9";
;
LOCATION"C516"
$SEC"1"
CDS_SEC"1"
PACK_TYPE"C0201"
VALUE"0.1UF"
VOLTAGE"10V"
MATERIAL"X7S"
TOLERANCE"10%"
CDS_LIB"pure_quanta"
PART_NUMBER"CH4102K6E00";
"B"
$PN"2"9;
"A"
$PN"1"11;
%"Q_CAP"
"1","(-2775,1150)","0","pure_quanta","I90";
;
LOCATION"C542"
$SEC"1"
CDS_SEC"1"
TOLERANCE"20%"
MATERIAL"X6S"
VOLTAGE"4V"
PACK_TYPE"0201"
VALUE"1UF"
CDS_LIB"pure_quanta"
PART_NUMBER"CH-10KMEE00";
"B"
$PN"2"12;
"A"
$PN"1"13;
%"Q_CAP"
"1","(-2225,1150)","0","pure_quanta","I91";
;
LOCATION"C545"
$SEC"1"
CDS_SEC"1"
VALUE"1UF"
TOLERANCE"20%"
MATERIAL"X6S"
PACK_TYPE"0201"
VOLTAGE"4V"
CDS_LIB"pure_quanta"
PART_NUMBER"CH-10KMEE00";
"B"
$PN"2"12;
"A"
$PN"1"13;
%"Q_CAP"
"1","(-1675,2925)","0","pure_quanta","I93";
;
LOCATION"C583"
$SEC"1"
CDS_SEC"1"
VALUE"0.1UF"
PACK_TYPE"C0201"
VOLTAGE"10V"
TOLERANCE"10%"
MATERIAL"X7S"
CDS_LIB"pure_quanta"
PART_NUMBER"CH4102K6E00";
"B"
$PN"2"4;
"A"
$PN"1"3;
%"Q_CAP"
"1","(-1375,2925)","0","pure_quanta","I94";
;
LOCATION"C566"
$SEC"1"
CDS_SEC"1"
PACK_TYPE"C0201"
MATERIAL"X7S"
VOLTAGE"10V"
TOLERANCE"10%"
VALUE"0.1UF"
CDS_LIB"pure_quanta"
PART_NUMBER"CH4102K6E00";
"B"
$PN"2"4;
"A"
$PN"1"3;
%"Q_CAP"
"1","(-450,5425)","0","pure_quanta","I95";
;
LOCATION"C7003"
$SEC"1"
CDS_SEC"1"
MATERIAL"X6S"
TOLERANCE"20%"
VOLTAGE"4V"
VALUE"47UF"
PACK_TYPE"C0805"
CDS_LIB"pure_quanta"
PART_NUMBER"CH647KMEA04";
"B"
$PN"2"2;
"A"
$PN"1"1;
%"Q_CAP"
"1","(-850,5450)","0","pure_quanta","I96";
;
LOCATION"C7002"
$SEC"1"
CDS_SEC"1"
PACK_TYPE"C0805"
MATERIAL"X6S"
VALUE"47UF"
VOLTAGE"4V"
TOLERANCE"20%"
CDS_LIB"pure_quanta"
PART_NUMBER"CH647KMEA04";
"B"
$PN"2"2;
"A"
$PN"1"1;
%"Q_CAPP"
"1","(-1150,5450)","0","pure_quanta","I97";
;
LOCATION"C7001"
$SEC"1"
CDS_SEC"1"
TOLERANCE"20%"
VALUE"470UF"
PACK_TYPE"SMLF"
MATERIAL"SPCAP"
VOLTAGE"2.5V"
CDS_LIB"pure_quanta"
PART_NUMBER"CH747LM8818";
"A"
$PN"1"1;
"B"
$PN"2"2;
%"Q_CAPP"
"1","(-1450,5450)","0","pure_quanta","I98";
;
LOCATION"C7000"
$SEC"1"
CDS_SEC"1"
VALUE"470UF"
PACK_TYPE"SMLF"
VOLTAGE"2.5V"
MATERIAL"SPCAP"
TOLERANCE"20%"
CDS_LIB"pure_quanta"
PART_NUMBER"CH747LM8818";
"A"
$PN"1"1;
"B"
$PN"2"2;
%"Q_CAPP"
"1","(-1050,2250)","0","pure_quanta","I99";
;
LOCATION"C7008"
$SEC"1"
CDS_SEC"1"
VALUE"470UF"
TOLERANCE"20%"
PACK_TYPE"SMLF"
VOLTAGE"2.5V"
MATERIAL"SPCAP"
CDS_LIB"pure_quanta"
PART_NUMBER"CH747LM8818";
"A"
$PN"1"3;
"B"
$PN"2"10;
END.
